(kicad_pcb
	(version 20241229)
	(generator "pcbnew")
	(generator_version "9.0")
	(general
		(thickness 1.711)
		(legacy_teardrops no)
	)
	(paper "A4")
	(title_block
		(title "Antmicro Baseboard for Jetson AGX Thor")
		(date "2026-02-18")
		(rev "1.1.0")
		(company "Antmicro Ltd")
		(comment 1 "www.antmicro.com")
		(comment 9 "footprints 589-592 of 1170")
	)
	(layers
		(0 "F.Cu" signal)
		(4 "In1.Cu" signal)
		(6 "In2.Cu" signal)
		(8 "In3.Cu" signal)
		(10 "In4.Cu" jumper)
		(12 "In5.Cu" signal)
		(14 "In6.Cu" signal)
		(16 "In7.Cu" signal)
		(18 "In8.Cu" signal)
		(2 "B.Cu" signal)
		(9 "F.Adhes" user "F.Adhesive")
		(11 "B.Adhes" user "B.Adhesive")
		(13 "F.Paste" user)
		(15 "B.Paste" user)
		(5 "F.SilkS" user "F.Silkscreen")
		(7 "B.SilkS" user "B.Silkscreen")
		(1 "F.Mask" user)
		(3 "B.Mask" user)
		(17 "Dwgs.User" user "User.Drawings")
		(19 "Cmts.User" user "User.Comments")
		(21 "Eco1.User" user "User.Eco1")
		(23 "Eco2.User" user "User.Eco2")
		(25 "Edge.Cuts" user)
		(27 "Margin" user)
		(31 "F.CrtYd" user "F.Courtyard")
		(29 "B.CrtYd" user "B.Courtyard")
		(35 "F.Fab" user)
		(33 "B.Fab" user)
	)
	(footprint "antmicro-footprints:Conn_Amphenol_SFP28_1x20_UE763GA202600T"
		(locked yes)
		(layer "F.Cu")
		(at 201.826 144.9 180)
		(property "Reference" "J12"
			(at -7.805 -6.2 0)
			(layer "F.SilkS")
			(effects
				(font
					(size 0.7 0.7)
					(thickness 0.15)
				)
				(justify right top)
			)
		)
		(property "Value" "Amphenol_SFP28_1x20_UE763GA202600T"
			(at -7.805 7.1 0)
			(layer "F.Fab")
			(effects
				(font
					(size 0.7 0.7)
					(thickness 0.15)
				)
				(justify right top)
			)
		)
		(property "Datasheet" "https://cdn.amphenol-cs.com/media/wysiwyg/files/documentation/datasheet/inputoutput/hsio_cn_ultraport_sfp.pdf"
			(at -8 12 0)
			(layer "F.Fab")
			(effects
				(font
					(size 0.7 0.7)
					(thickness 0.15)
				)
				(justify right top)
			)
		)
		(property "Description" "20 Position SFP28 Receptacle with no Cage, Right Angle"
			(at -0.702 23.301 0)
			(layer "F.Fab")
			(effects
				(font
					(size 0.7 0.7)
					(thickness 0.15)
				)
				(justify right top)
			)
		)
		(property "MPN" "UE763GA202600T"
			(at 0 0 180)
			(unlocked yes)
			(layer "F.Fab")
			(hide yes)
			(effects
				(font
					(size 1 1)
					(thickness 0.15)
				)
			)
		)
		(property "Manufacturer" "Amphenol"
			(at 0 0 180)
			(unlocked yes)
			(layer "F.Fab")
			(hide yes)
			(effects
				(font
					(size 1 1)
					(thickness 0.15)
				)
			)
		)
		(property "Author" "Antmicro"
			(at 0 0 180)
			(unlocked yes)
			(layer "F.Fab")
			(hide yes)
			(effects
				(font
					(size 1 1)
					(thickness 0.15)
				)
			)
		)
		(property "License" "Apache-2.0"
			(at 0 0 180)
			(unlocked yes)
			(layer "F.Fab")
			(hide yes)
			(effects
				(font
					(size 1 1)
					(thickness 0.15)
				)
			)
		)
		(sheetname "/SFP/")
		(sheetfile "sfp.kicad_sch")
		(attr smd)
		(fp_circle
			(center -4.7 -3.9)
			(end -4.65 -3.9)
			(stroke
				(width 0.15)
				(type solid)
			)
			(fill yes)
			(layer "F.SilkS")
		)
		(fp_rect
			(start -4.9 -6)
			(end 4.9 6)
			(stroke
				(width 0.05)
				(type solid)
			)
			(fill no)
			(layer "F.CrtYd")
		)
		(fp_text user "Author: Antmicro"
			(at -7.805 10.7 0)
			(layer "F.Fab")
			(effects
				(font
					(size 0.7 0.7)
					(thickness 0.15)
				)
				(justify right top)
			)
		)
		(fp_text user "${REFERENCE}"
			(at -7.805 9.5 0)
			(layer "F.Fab")
			(effects
				(font
					(size 0.7 0.7)
					(thickness 0.15)
				)
				(justify right top)
			)
		)
		(fp_text user "License: Apache-2.0"
			(at -7.805 8.3 0)
			(layer "F.Fab")
			(effects
				(font
					(size 0.7 0.7)
					(thickness 0.15)
				)
				(justify right top)
			)
		)
		(pad "" np_thru_hole circle
			(at 0 -4.8 90)
			(size 1.6 1.6)
			(drill 1.6)
			(layers "*.Cu" "*.Mask")
		)
		(pad "" np_thru_hole circle
			(at 0 4.8 90)
			(size 1.6 1.6)
			(drill 1.6)
			(layers "*.Cu" "*.Mask")
		)
		(pad "1" smd rect
			(at -4.1 -3.4 90)
			(size 0.5 2)
			(layers "F.Cu" "F.Mask" "F.Paste")
			(net 1 "GND")
			(pinfunction "V_{EE}(T)")
			(pintype "passive")
			(solder_mask_margin 0.102)
		)
		(pad "2" smd rect
			(at -4.1 -2.6 90)
			(size 0.5 2)
			(layers "F.Cu" "F.Mask" "F.Paste")
			(net 1371 "Net-(J12-TX_{FAULT})")
			(pinfunction "TX_{FAULT}")
			(pintype "open_collector")
			(solder_mask_margin 0.102)
		)
		(pad "3" smd rect
			(at -4.1 -1.8 90)
			(size 0.5 2)
			(layers "F.Cu" "F.Mask" "F.Paste")
			(net 1367 "Net-(J12-TX_{DISABLE})")
			(pinfunction "TX_{DISABLE}")
			(pintype "input")
			(solder_mask_margin 0.102)
		)
		(pad "4" smd rect
			(at -4.1 -1 90)
			(size 0.5 2)
			(layers "F.Cu" "F.Mask" "F.Paste")
			(net 824 "/SFP/SDA_SFP")
			(pinfunction "SDA")
			(pintype "bidirectional")
			(solder_mask_margin 0.102)
		)
		(pad "5" smd rect
			(at -4.1 -0.2 90)
			(size 0.5 2)
			(layers "F.Cu" "F.Mask" "F.Paste")
			(net 823 "/SFP/SCL_SFP")
			(pinfunction "SCL")
			(pintype "bidirectional")
			(solder_mask_margin 0.102)
		)
		(pad "6" smd rect
			(at -4.1 0.6 90)
			(size 0.5 2)
			(layers "F.Cu" "F.Mask" "F.Paste")
			(net 1296 "/SFP/SFP_MOD_ABS")
			(pinfunction "MOD_{ABS}")
			(pintype "passive")
			(solder_mask_margin 0.102)
		)
		(pad "7" smd rect
			(at -4.1 1.4 90)
			(size 0.5 2)
			(layers "F.Cu" "F.Mask" "F.Paste")
			(net 1368 "Net-(J12-RS0)")
			(pinfunction "RS0")
			(pintype "input")
			(solder_mask_margin 0.102)
		)
		(pad "8" smd rect
			(at -4.1 2.2 90)
			(size 0.5 2)
			(layers "F.Cu" "F.Mask" "F.Paste")
			(net 1370 "Net-(J12-RX_{LOS})")
			(pinfunction "RX_{LOS}")
			(pintype "open_collector")
			(solder_mask_margin 0.102)
		)
		(pad "9" smd rect
			(at -4.1 3 90)
			(size 0.5 2)
			(layers "F.Cu" "F.Mask" "F.Paste")
			(net 1369 "Net-(J12-RS1)")
			(pinfunction "RS1")
			(pintype "input")
			(solder_mask_margin 0.102)
		)
		(pad "10" smd rect
			(at -4.1 3.8 90)
			(size 0.5 2)
			(layers "F.Cu" "F.Mask" "F.Paste")
			(net 1 "GND")
			(pinfunction "V_{EE}(R)")
			(pintype "passive")
			(solder_mask_margin 0.102)
		)
		(pad "11" smd rect
			(at 4.1 3.4 90)
			(size 0.5 2)
			(layers "F.Cu" "F.Mask" "F.Paste")
			(net 1 "GND")
			(pinfunction "V_{EE}(R)")
			(pintype "passive")
			(solder_mask_margin 0.102)
		)
		(pad "12" smd rect
			(at 4.1 2.6 90)
			(size 0.5 2)
			(layers "F.Cu" "F.Mask" "F.Paste")
			(net 30 "/SFP/SFI_CONN_RX_N")
			(pinfunction "RD-")
			(pintype "output")
			(solder_mask_margin 0.102)
		)
		(pad "13" smd rect
			(at 4.1 1.8 90)
			(size 0.5 2)
			(layers "F.Cu" "F.Mask" "F.Paste")
			(net 27 "/SFP/SFI_CONN_RX_P")
			(pinfunction "RD+")
			(pintype "output")
			(solder_mask_margin 0.102)
		)
		(pad "14" smd rect
			(at 4.1 1 90)
			(size 0.5 2)
			(layers "F.Cu" "F.Mask" "F.Paste")
			(net 1 "GND")
			(pinfunction "V_{EE}(R)")
			(pintype "passive")
			(solder_mask_margin 0.102)
		)
		(pad "15" smd rect
			(at 4.1 0.2 90)
			(size 0.5 2)
			(layers "F.Cu" "F.Mask" "F.Paste")
			(net 2 "+3V3")
			(pinfunction "V_{CC}(R)")
			(pintype "power_in")
			(solder_mask_margin 0.102)
		)
		(pad "16" smd rect
			(at 4.1 -0.6 90)
			(size 0.5 2)
			(layers "F.Cu" "F.Mask" "F.Paste")
			(net 2 "+3V3")
			(pinfunction "V_{CC}(T)")
			(pintype "power_in")
			(solder_mask_margin 0.102)
		)
		(pad "17" smd rect
			(at 4.1 -1.4 90)
			(size 0.5 2)
			(layers "F.Cu" "F.Mask" "F.Paste")
			(net 1 "GND")
			(pinfunction "V_{EE}(T)")
			(pintype "passive")
			(solder_mask_margin 0.102)
		)
		(pad "18" smd rect
			(at 4.1 -2.2 90)
			(size 0.5 2)
			(layers "F.Cu" "F.Mask" "F.Paste")
			(net 21 "/SFP/SFI_CONN_TX_P")
			(pinfunction "TD+")
			(pintype "input")
			(solder_mask_margin 0.102)
		)
		(pad "19" smd rect
			(at 4.1 -3 90)
			(size 0.5 2)
			(layers "F.Cu" "F.Mask" "F.Paste")
			(net 22 "/SFP/SFI_CONN_TX_N")
			(pinfunction "TD-")
			(pintype "input")
			(solder_mask_margin 0.102)
		)
		(pad "20" smd rect
			(at 4.1 -3.8 90)
			(size 0.5 2)
			(layers "F.Cu" "F.Mask" "F.Paste")
			(net 1 "GND")
			(pinfunction "V_{EE}(T)")
			(pintype "passive")
			(solder_mask_margin 0.102)
		)
	)
	(footprint "antmicro-footprints:C_0402_1005Metric"
		(layer "F.Cu")
		(at 206.75 89.470856 180)
		(descr "Capacitor SMD 0402")
		(tags "capacitor SMD 0402")
		(property "Reference" "C317"
			(at -0.95 -0.429144 180)
			(layer "F.SilkS")
			(effects
				(font
					(size 0.7 0.7)
					(thickness 0.15)
				)
				(justify left bottom)
			)
		)
		(property "Value" "C_100n_0402"
			(at -1.022927 2.155213 180)
			(layer "F.Fab")
			(effects
				(font
					(size 0.7 0.7)
					(thickness 0.15)
				)
				(justify left bottom)
			)
		)
		(property "Datasheet" "https://www.murata.com/products/productdetail?partno=GRM155R61H104KE14%23"
			(at 0 0 180)
			(layer "F.Fab")
			(hide yes)
			(effects
				(font
					(size 1.27 1.27)
					(thickness 0.15)
				)
			)
		)
		(property "Description" "SMD Multilayer Ceramic Capacitor, 0.1 µF, 50 V, 0402 [1005 Metric], ± 10%, X5R, GRM Series"
			(at 0 0 180)
			(layer "F.Fab")
			(hide yes)
			(effects
				(font
					(size 1.27 1.27)
					(thickness 0.15)
				)
			)
		)
		(property "Manufacturer" "Murata"
			(at 0 0 180)
			(unlocked yes)
			(layer "F.Fab")
			(hide yes)
			(effects
				(font
					(size 1 1)
					(thickness 0.15)
				)
			)
		)
		(property "MPN" "GRM155R61H104KE14D"
			(at 0 0 180)
			(unlocked yes)
			(layer "F.Fab")
			(hide yes)
			(effects
				(font
					(size 1 1)
					(thickness 0.15)
				)
			)
		)
		(property "Val" "100n"
			(at 0 0 180)
			(unlocked yes)
			(layer "F.Fab")
			(hide yes)
			(effects
				(font
					(size 1 1)
					(thickness 0.15)
				)
			)
		)
		(property "License" "Apache-2.0"
			(at 0 0 180)
			(unlocked yes)
			(layer "F.Fab")
			(hide yes)
			(effects
				(font
					(size 1 1)
					(thickness 0.15)
				)
			)
		)
		(property "Author" "Antmicro"
			(at 0 0 180)
			(unlocked yes)
			(layer "F.Fab")
			(hide yes)
			(effects
				(font
					(size 1 1)
					(thickness 0.15)
				)
			)
		)
		(property "Voltage" "50V"
			(at 0 0 180)
			(unlocked yes)
			(layer "F.Fab")
			(hide yes)
			(effects
				(font
					(size 1 1)
					(thickness 0.15)
				)
			)
		)
		(property "Dielectric" "X5R"
			(at 0 0 180)
			(unlocked yes)
			(layer "F.Fab")
			(hide yes)
			(effects
				(font
					(size 1 1)
					(thickness 0.15)
				)
			)
		)
		(sheetname "/SoM_IO2/")
		(sheetfile "som_io2.kicad_sch")
		(attr smd)
		(fp_rect
			(start -0.925 -0.47)
			(end 0.925 0.47)
			(stroke
				(width 0.05)
				(type default)
			)
			(fill no)
			(layer "F.CrtYd")
		)
		(fp_line
			(start 0.504 0.248)
			(end -0.494 0.248)
			(stroke
				(width 0.15)
				(type solid)
			)
			(layer "F.Fab")
		)
		(fp_line
			(start 0.504 -0.25)
			(end 0.504 0.248)
			(stroke
				(width 0.15)
				(type solid)
			)
			(layer "F.Fab")
		)
		(fp_line
			(start -0.494 0.248)
			(end -0.494 -0.25)
			(stroke
				(width 0.15)
				(type solid)
			)
			(layer "F.Fab")
		)
		(fp_line
			(start -0.494 -0.25)
			(end 0.504 -0.25)
			(stroke
				(width 0.15)
				(type solid)
			)
			(layer "F.Fab")
		)
		(fp_text user "${REFERENCE}"
			(at -0.939 4.599 180)
			(layer "F.Fab")
			(effects
				(font
					(size 0.7 0.7)
					(thickness 0.15)
				)
				(justify left bottom)
			)
		)
		(fp_text user "License: Apache-2.0"
			(at -0.939 5.799 180)
			(layer "F.Fab")
			(effects
				(font
					(size 0.7 0.7)
					(thickness 0.15)
				)
				(justify left bottom)
			)
		)
		(fp_text user "Author: Antmicro"
			(at -0.939 3.399 180)
			(layer "F.Fab")
			(effects
				(font
					(size 0.7 0.7)
					(thickness 0.15)
				)
				(justify left bottom)
			)
		)
		(pad "1" smd roundrect
			(at -0.48 0 180)
			(size 0.59 0.64)
			(layers "F.Cu" "F.Mask" "F.Paste")
			(roundrect_rratio 0.25)
			(net 792 "/SoM_IO2/DP0.TX1-")
			(pintype "passive")
		)
		(pad "2" smd roundrect
			(at 0.48 0 180)
			(size 0.59 0.64)
			(layers "F.Cu" "F.Mask" "F.Paste")
			(roundrect_rratio 0.25)
			(net 597 "/SoM_IO2/DP0.TX1_C-")
			(pintype "passive")
		)
	)
	(footprint "antmicro-footprints:C_0402_1005Metric"
		(layer "F.Cu")
		(at 193.126 147.1 180)
		(descr "Capacitor SMD 0402")
		(tags "capacitor SMD 0402")
		(property "Reference" "C57"
			(at 3.1 -0.5 180)
			(layer "F.SilkS")
			(effects
				(font
					(size 0.7 0.7)
					(thickness 0.15)
				)
				(justify left bottom)
			)
		)
		(property "Value" "C_100n_0402"
			(at -1.022927 2.155213 180)
			(layer "F.Fab")
			(effects
				(font
					(size 0.7 0.7)
					(thickness 0.15)
				)
				(justify left bottom)
			)
		)
		(property "Datasheet" "https://www.murata.com/products/productdetail?partno=GRM155R61H104KE14%23"
			(at 0 0 180)
			(layer "F.Fab")
			(hide yes)
			(effects
				(font
					(size 1.27 1.27)
					(thickness 0.15)
				)
			)
		)
		(property "Description" "SMD Multilayer Ceramic Capacitor, 0.1 µF, 50 V, 0402 [1005 Metric], ± 10%, X5R, GRM Series"
			(at 0 0 180)
			(layer "F.Fab")
			(hide yes)
			(effects
				(font
					(size 1.27 1.27)
					(thickness 0.15)
				)
			)
		)
		(property "Manufacturer" "Murata"
			(at 0 0 180)
			(unlocked yes)
			(layer "F.Fab")
			(hide yes)
			(effects
				(font
					(size 1 1)
					(thickness 0.15)
				)
			)
		)
		(property "MPN" "GRM155R61H104KE14D"
			(at 0 0 180)
			(unlocked yes)
			(layer "F.Fab")
			(hide yes)
			(effects
				(font
					(size 1 1)
					(thickness 0.15)
				)
			)
		)
		(property "Val" "100n"
			(at 0 0 180)
			(unlocked yes)
			(layer "F.Fab")
			(hide yes)
			(effects
				(font
					(size 1 1)
					(thickness 0.15)
				)
			)
		)
		(property "License" "Apache-2.0"
			(at 0 0 180)
			(unlocked yes)
			(layer "F.Fab")
			(hide yes)
			(effects
				(font
					(size 1 1)
					(thickness 0.15)
				)
			)
		)
		(property "Author" "Antmicro"
			(at 0 0 180)
			(unlocked yes)
			(layer "F.Fab")
			(hide yes)
			(effects
				(font
					(size 1 1)
					(thickness 0.15)
				)
			)
		)
		(property "Voltage" "50V"
			(at 0 0 180)
			(unlocked yes)
			(layer "F.Fab")
			(hide yes)
			(effects
				(font
					(size 1 1)
					(thickness 0.15)
				)
			)
		)
		(property "Dielectric" "X5R"
			(at 0 0 180)
			(unlocked yes)
			(layer "F.Fab")
			(hide yes)
			(effects
				(font
					(size 1 1)
					(thickness 0.15)
				)
			)
		)
		(property "Public" "False"
			(at 0 0 180)
			(unlocked yes)
			(layer "F.Fab")
			(hide yes)
			(effects
				(font
					(size 1 1)
					(thickness 0.15)
				)
			)
		)
		(sheetname "/SFP/")
		(sheetfile "sfp.kicad_sch")
		(attr smd)
		(fp_rect
			(start -0.925 -0.47)
			(end 0.925 0.47)
			(stroke
				(width 0.05)
				(type default)
			)
			(fill no)
			(layer "F.CrtYd")
		)
		(fp_line
			(start 0.504 0.248)
			(end -0.494 0.248)
			(stroke
				(width 0.15)
				(type solid)
			)
			(layer "F.Fab")
		)
		(fp_line
			(start 0.504 -0.25)
			(end 0.504 0.248)
			(stroke
				(width 0.15)
				(type solid)
			)
			(layer "F.Fab")
		)
		(fp_line
			(start -0.494 0.248)
			(end -0.494 -0.25)
			(stroke
				(width 0.15)
				(type solid)
			)
			(layer "F.Fab")
		)
		(fp_line
			(start -0.494 -0.25)
			(end 0.504 -0.25)
			(stroke
				(width 0.15)
				(type solid)
			)
			(layer "F.Fab")
		)
		(fp_text user "Author: Antmicro"
			(at -0.939 3.399 180)
			(layer "F.Fab")
			(effects
				(font
					(size 0.7 0.7)
					(thickness 0.15)
				)
				(justify left bottom)
			)
		)
		(fp_text user "${REFERENCE}"
			(at -0.939 4.599 180)
			(layer "F.Fab")
			(effects
				(font
					(size 0.7 0.7)
					(thickness 0.15)
				)
				(justify left bottom)
			)
		)
		(fp_text user "License: Apache-2.0"
			(at -0.939 5.799 180)
			(layer "F.Fab")
			(effects
				(font
					(size 0.7 0.7)
					(thickness 0.15)
				)
				(justify left bottom)
			)
		)
		(pad "1" smd roundrect
			(at -0.48 0 180)
			(size 0.59 0.64)
			(layers "F.Cu" "F.Mask" "F.Paste")
			(roundrect_rratio 0.25)
			(net 21 "/SFP/SFI_CONN_TX_P")
			(pintype "passive")
		)
		(pad "2" smd roundrect
			(at 0.48 0 180)
			(size 0.59 0.64)
			(layers "F.Cu" "F.Mask" "F.Paste")
			(roundrect_rratio 0.25)
			(net 106 "/SFP/SFI.TX+")
			(pintype "passive")
		)
	)
	(footprint "antmicro-footprints:R_0402_1005Metric"
		(layer "F.Cu")
		(at 94 65.45 180)
		(descr "Resistor SMD 0402")
		(tags "resistor SMD 0402")
		(property "Reference" "R24"
			(at -9.1 -0.45 0)
			(layer "F.SilkS")
			(effects
				(font
					(size 0.7 0.7)
					(thickness 0.15)
				)
				(justify right top)
			)
		)
		(property "Value" "R_10k_0402"
			(at -1.011843 1.772046 0)
			(layer "F.Fab")
			(effects
				(font
					(size 0.7 0.7)
					(thickness 0.15)
				)
				(justify right top)
			)
		)
		(property "Datasheet" "https://www.bourns.com/docs/product-datasheets/cr.pdf"
			(at 0 0 0)
			(layer "F.Fab")
			(hide yes)
			(effects
				(font
					(size 1.27 1.27)
					(thickness 0.15)
				)
			)
		)
		(property "Description" "SMD Chip Resistor, 10 kohm, ± 1%, 62.5 mW, 0402 [1005 Metric], Thick Film, General Purpose"
			(at 0 0 0)
			(layer "F.Fab")
			(hide yes)
			(effects
				(font
					(size 1.27 1.27)
					(thickness 0.15)
				)
			)
		)
		(property "MPN" "CR0402-FX-1002GLF"
			(at 0 0 180)
			(unlocked yes)
			(layer "F.Fab")
			(hide yes)
			(effects
				(font
					(size 1 1)
					(thickness 0.15)
				)
			)
		)
		(property "Manufacturer" "Bourns"
			(at 0 0 180)
			(unlocked yes)
			(layer "F.Fab")
			(hide yes)
			(effects
				(font
					(size 1 1)
					(thickness 0.15)
				)
			)
		)
		(property "License" "Apache-2.0"
			(at 0 0 180)
			(unlocked yes)
			(layer "F.Fab")
			(hide yes)
			(effects
				(font
					(size 1 1)
					(thickness 0.15)
				)
			)
		)
		(property "Author" "Antmicro"
			(at 0 0 180)
			(unlocked yes)
			(layer "F.Fab")
			(hide yes)
			(effects
				(font
					(size 1 1)
					(thickness 0.15)
				)
			)
		)
		(property "Val" "10k"
			(at 0 0 180)
			(unlocked yes)
			(layer "F.Fab")
			(hide yes)
			(effects
				(font
					(size 1 1)
					(thickness 0.15)
				)
			)
		)
		(property "Tolerance" "1%"
			(at 0 0 180)
			(unlocked yes)
			(layer "F.Fab")
			(hide yes)
			(effects
				(font
					(size 1 1)
					(thickness 0.15)
				)
			)
		)
		(sheetname "/SoM_Power/")
		(sheetfile "som_power.kicad_sch")
		(attr smd)
		(fp_poly
			(pts
				(xy -0.925 -0.47) (xy 0.925 -0.47) (xy 0.925 0.47) (xy -0.925 0.47)
			)
			(stroke
				(width 0.05)
				(type default)
			)
			(fill no)
			(layer "F.CrtYd")
		)
		(fp_poly
			(pts
				(xy -0.5 -0.25) (xy 0.5 -0.25) (xy 0.5 0.25) (xy -0.5 0.25)
			)
			(stroke
				(width 0.15)
				(type solid)
			)
			(fill no)
			(layer "F.Fab")
		)
		(fp_text user "License: Apache-2.0"
			(at -0.949999 5.169 0)
			(layer "F.Fab")
			(effects
				(font
					(size 0.7 0.7)
					(thickness 0.15)
				)
				(justify right top)
			)
		)
		(fp_text user "Author: Antmicro"
			(at -0.95 4.169 0)
			(layer "F.Fab")
			(effects
				(font
					(size 0.7 0.7)
					(thickness 0.15)
				)
				(justify right top)
			)
		)
		(fp_text user "${REFERENCE}"
			(at -0.95 3.168 0)
			(layer "F.Fab")
			(effects
				(font
					(size 0.7 0.7)
					(thickness 0.15)
				)
				(justify right top)
			)
		)
		(pad "1" smd roundrect
			(at -0.48 0 180)
			(size 0.59 0.64)
			(layers "F.Cu" "F.Mask" "F.Paste")
			(roundrect_rratio 0.25)
			(net 1285 "/SoM_Power/VIN_PWR_ON")
			(pintype "passive")
		)
		(pad "2" smd roundrect
			(at 0.48 0 180)
			(size 0.59 0.64)
			(layers "F.Cu" "F.Mask" "F.Paste")
			(roundrect_rratio 0.25)
			(net 1304 "Net-(U74-2Y)")
			(pintype "passive")
		)
	)
)
